# S9S_MB_2U (Grand Teton) — schematic netlist excerpt (pin names and nets, part order shuffled) for the footprints in the layout excerpt that follows; sources: Cadence DE-HDL packaged netlist, KiCad conversion of 03242023_DA0F0TMBIJ0_F0T_Motherboard_J_brd_V01_OCP.brd

R1458  Q_RES  10K 1% CHIP  pkg 0402LF  page 204 : A = P3V3_AUX ; B = IRQ_SMI_ACTIVE_N
PR443  Q_RES  0 5% EMPTY  pkg 0402LF  page 276 : A = P3V3 ; B = PVCCFA_EHV_CPU0_PVCC
C491  Q_CAP  47UF 4V 20% X6S  pkg C0805  page 75 : A = PVCCD_HV_CPU0 ; B = GND

(kicad_pcb
	(version 20260206)
	(generator "pcbnew")
	(generator_version "10.0")
	(general
		(thickness 1.6)
		(legacy_teardrops no)
	)
	(paper "A4")
	(title_block
		(title "03242023_DA0F0TMBIJ0_F0T_Motherboard_J_brd_V01_OCP.brd")
		(comment 1 "Grand Teton / footprints 4295-4297 of 6105")
	)
	(layers
		(0 "F.Cu" signal "TOP")
		(4 "In1.Cu" signal "GND")
		(6 "In2.Cu" signal "IN1")
		(8 "In3.Cu" signal "GND1")
		(10 "In4.Cu" signal "IN2")
		(12 "In5.Cu" signal "GND2")
		(14 "In6.Cu" signal "IN3")
		(16 "In7.Cu" signal "GND3")
		(18 "In8.Cu" signal "VCC")
		(20 "In9.Cu" signal "VCC1")
		(22 "In10.Cu" signal "GND4")
		(24 "In11.Cu" signal "IN4")
		(26 "In12.Cu" signal "GND5")
		(28 "In13.Cu" signal "IN5")
		(30 "In14.Cu" signal "GND6")
		(32 "In15.Cu" signal "IN6")
		(34 "In16.Cu" signal "GND7")
		(2 "B.Cu" signal "BOTTOM")
		(9 "F.Adhes" user "F.Adhesive")
		(11 "B.Adhes" user "B.Adhesive")
		(13 "F.Paste" user "Package Geometry/Pastemask Top")
		(15 "B.Paste" user "Package Geometry/Pastemask Bottom")
		(5 "F.SilkS" user "Ref Des/Silkscreen Top")
		(7 "B.SilkS" user "Ref Des/Silkscreen Bottom")
		(1 "F.Mask" user "Board Geometry/Soldermask Top")
		(3 "B.Mask" user "Board Geometry/Soldermask Bottom")
		(17 "Dwgs.User" user "User.Drawings")
		(19 "Cmts.User" user "User.Comments")
		(21 "Eco1.User" user "User.Eco1")
		(23 "Eco2.User" user "User.Eco2")
		(25 "Edge.Cuts" user "Board Geometry/Outline")
		(27 "Margin" user)
		(31 "F.CrtYd" user "Package Geometry/Place Bound Top")
		(29 "B.CrtYd" user "Package Geometry/Place Bound Bottom")
		(35 "F.Fab" user "Ref Des/Assembly Top")
		(33 "B.Fab" user "Ref Des/Assembly Bottom")
	)
	(footprint ""
		(layer "B.Cu")
		(at 343.050368 -31.678372 180)
		(property "Reference" "R1458"
			(at 0 0 0)
			(layer "B.SilkS")
			(hide yes)
			(effects
				(font
					(size 1.27 1.27)
				)
				(justify mirror)
			)
		)
		(property "Value" ""
			(at 0 0 0)
			(layer "B.Fab")
			(effects
				(font
					(size 1.27 1.27)
				)
				(justify mirror)
			)
		)
		(duplicate_pad_numbers_are_jumpers no)
		(fp_line
			(start 0.7874 0.4064)
			(end 0.7874 -0.4064)
			(stroke
				(width 0.1524)
				(type default)
			)
			(layer "B.SilkS")
		)
		(fp_line
			(start 0.7874 -0.4064)
			(end -0.7874 -0.4064)
			(stroke
				(width 0.1524)
				(type default)
			)
			(layer "B.SilkS")
		)
		(fp_line
			(start -0.7874 0.4064)
			(end 0.7874 0.4064)
			(stroke
				(width 0.1524)
				(type default)
			)
			(layer "B.SilkS")
		)
		(fp_line
			(start -0.7874 -0.4064)
			(end -0.7874 0.4064)
			(stroke
				(width 0.1524)
				(type default)
			)
			(layer "B.SilkS")
		)
		(fp_line
			(start 0.67945 0.3048)
			(end 0.67945 -0.305054)
			(stroke
				(width 0.1)
				(type default)
			)
			(layer "B.Fab")
		)
		(fp_line
			(start 0.67945 -0.305054)
			(end 0.12065 -0.305054)
			(stroke
				(width 0.1)
				(type default)
			)
			(layer "B.Fab")
		)
		(fp_line
			(start 0.12065 0.3048)
			(end 0.67945 0.3048)
			(stroke
				(width 0.1)
				(type default)
			)
			(layer "B.Fab")
		)
		(fp_line
			(start 0.12065 0.2794)
			(end 0.12065 0.3048)
			(stroke
				(width 0.1)
				(type default)
			)
			(layer "B.Fab")
		)
		(fp_line
			(start 0.12065 -0.2794)
			(end -0.12065 -0.2794)
			(stroke
				(width 0.1)
				(type default)
			)
			(layer "B.Fab")
		)
		(fp_line
			(start 0.12065 -0.305054)
			(end 0.12065 -0.2794)
			(stroke
				(width 0.1)
				(type default)
			)
			(layer "B.Fab")
		)
		(fp_line
			(start -0.120396 0.3048)
			(end -0.120396 0.2794)
			(stroke
				(width 0.1)
				(type default)
			)
			(layer "B.Fab")
		)
		(fp_line
			(start -0.120396 0.2794)
			(end 0.12065 0.2794)
			(stroke
				(width 0.1)
				(type default)
			)
			(layer "B.Fab")
		)
		(fp_line
			(start -0.12065 -0.2794)
			(end -0.12065 -0.3048)
			(stroke
				(width 0.1)
				(type default)
			)
			(layer "B.Fab")
		)
		(fp_line
			(start -0.12065 -0.3048)
			(end -0.67945 -0.3048)
			(stroke
				(width 0.1)
				(type default)
			)
			(layer "B.Fab")
		)
		(fp_line
			(start -0.67945 0.3048)
			(end -0.120396 0.3048)
			(stroke
				(width 0.1)
				(type default)
			)
			(layer "B.Fab")
		)
		(fp_line
			(start -0.67945 -0.3048)
			(end -0.67945 0.3048)
			(stroke
				(width 0.1)
				(type default)
			)
			(layer "B.Fab")
		)
		(pad "1" smd circle
			(at 0.40005 0)
			(size 0 0)
			(layers "B.Cu" "B.Mask" "B.Paste")
			(net "P3V3_AUX")
		)
		(pad "2" smd circle
			(at -0.40005 0)
			(size 0 0)
			(layers "B.Cu" "B.Mask" "B.Paste")
			(net "IRQ_SMI_ACTIVE_N")
		)
	)
	(footprint ""
		(layer "B.Cu")
		(at 421.92448 -156.378148 90)
		(property "Reference" "PR443"
			(at 0 0 90)
			(layer "B.SilkS")
			(hide yes)
			(effects
				(font
					(size 1.27 1.27)
				)
				(justify mirror)
			)
		)
		(property "Value" ""
			(at 0 0 90)
			(layer "B.Fab")
			(effects
				(font
					(size 1.27 1.27)
				)
				(justify mirror)
			)
		)
		(duplicate_pad_numbers_are_jumpers no)
		(fp_line
			(start 0.7874 -0.4064)
			(end -0.7874 -0.4064)
			(stroke
				(width 0.1524)
				(type default)
			)
			(layer "B.SilkS")
		)
		(fp_line
			(start -0.7874 -0.4064)
			(end -0.7874 0.4064)
			(stroke
				(width 0.1524)
				(type default)
			)
			(layer "B.SilkS")
		)
		(fp_line
			(start 0.7874 0.4064)
			(end 0.7874 -0.4064)
			(stroke
				(width 0.1524)
				(type default)
			)
			(layer "B.SilkS")
		)
		(fp_line
			(start -0.7874 0.4064)
			(end 0.7874 0.4064)
			(stroke
				(width 0.1524)
				(type default)
			)
			(layer "B.SilkS")
		)
		(fp_line
			(start 0.67945 -0.305054)
			(end 0.12065 -0.305054)
			(stroke
				(width 0.1)
				(type default)
			)
			(layer "B.Fab")
		)
		(fp_line
			(start 0.12065 -0.305054)
			(end 0.12065 -0.2794)
			(stroke
				(width 0.1)
				(type default)
			)
			(layer "B.Fab")
		)
		(fp_line
			(start -0.12065 -0.3048)
			(end -0.67945 -0.3048)
			(stroke
				(width 0.1)
				(type default)
			)
			(layer "B.Fab")
		)
		(fp_line
			(start -0.67945 -0.3048)
			(end -0.67945 0.3048)
			(stroke
				(width 0.1)
				(type default)
			)
			(layer "B.Fab")
		)
		(fp_line
			(start 0.12065 -0.2794)
			(end -0.12065 -0.2794)
			(stroke
				(width 0.1)
				(type default)
			)
			(layer "B.Fab")
		)
		(fp_line
			(start -0.12065 -0.2794)
			(end -0.12065 -0.3048)
			(stroke
				(width 0.1)
				(type default)
			)
			(layer "B.Fab")
		)
		(fp_line
			(start 0.12065 0.2794)
			(end 0.12065 0.3048)
			(stroke
				(width 0.1)
				(type default)
			)
			(layer "B.Fab")
		)
		(fp_line
			(start -0.120396 0.2794)
			(end 0.12065 0.2794)
			(stroke
				(width 0.1)
				(type default)
			)
			(layer "B.Fab")
		)
		(fp_line
			(start 0.67945 0.3048)
			(end 0.67945 -0.305054)
			(stroke
				(width 0.1)
				(type default)
			)
			(layer "B.Fab")
		)
		(fp_line
			(start 0.12065 0.3048)
			(end 0.67945 0.3048)
			(stroke
				(width 0.1)
				(type default)
			)
			(layer "B.Fab")
		)
		(fp_line
			(start -0.120396 0.3048)
			(end -0.120396 0.2794)
			(stroke
				(width 0.1)
				(type default)
			)
			(layer "B.Fab")
		)
		(fp_line
			(start -0.67945 0.3048)
			(end -0.120396 0.3048)
			(stroke
				(width 0.1)
				(type default)
			)
			(layer "B.Fab")
		)
		(pad "1" smd circle
			(at 0.40005 0 270)
			(size 0 0)
			(layers "B.Cu" "B.Mask" "B.Paste")
			(net "P3V3")
		)
		(pad "2" smd circle
			(at -0.40005 0 270)
			(size 0 0)
			(layers "B.Cu" "B.Mask" "B.Paste")
			(net "PVCCFA_EHV_CPU0_PVCC")
		)
	)
	(footprint ""
		(layer "B.Cu")
		(at 367.898934 -248.498106 -90)
		(property "Reference" "C491"
			(at 0 0 90)
			(layer "B.SilkS")
			(hide yes)
			(effects
				(font
					(size 1.27 1.27)
				)
				(justify mirror)
			)
		)
		(property "Value" ""
			(at 0 0 90)
			(layer "B.Fab")
			(effects
				(font
					(size 1.27 1.27)
				)
				(justify mirror)
			)
		)
		(duplicate_pad_numbers_are_jumpers no)
		(fp_line
			(start -1.524 0.762)
			(end 1.524 0.762)
			(stroke
				(width 0.1524)
				(type default)
			)
			(layer "B.SilkS")
		)
		(fp_line
			(start 1.524 0.762)
			(end 1.524 -0.762)
			(stroke
				(width 0.1524)
				(type default)
			)
			(layer "B.SilkS")
		)
		(fp_line
			(start -1.524 -0.762)
			(end -1.524 0.762)
			(stroke
				(width 0.1524)
				(type default)
			)
			(layer "B.SilkS")
		)
		(fp_line
			(start 1.524 -0.762)
			(end -1.524 -0.762)
			(stroke
				(width 0.1524)
				(type default)
			)
			(layer "B.SilkS")
		)
		(fp_line
			(start -1.1049 0.724916)
			(end -1.1049 -0.724916)
			(stroke
				(width 0.1)
				(type default)
			)
			(layer "B.Fab")
		)
		(fp_line
			(start 1.1049 0.724916)
			(end -1.1049 0.724916)
			(stroke
				(width 0.1)
				(type default)
			)
			(layer "B.Fab")
		)
		(fp_line
			(start -1.1049 -0.724916)
			(end 1.1049 -0.724916)
			(stroke
				(width 0.1)
				(type default)
			)
			(layer "B.Fab")
		)
		(fp_line
			(start 1.1049 -0.724916)
			(end 1.1049 0.724916)
			(stroke
				(width 0.1)
				(type default)
			)
			(layer "B.Fab")
		)
		(pad "1" smd rect
			(at 0.889 0 270)
			(size 1.016 1.27)
			(layers "B.Cu" "B.Mask" "B.Paste")
			(net "PVCCD_HV_CPU0")
		)
		(pad "2" smd rect
			(at -0.889 0 270)
			(size 1.016 1.27)
			(layers "B.Cu" "B.Mask" "B.Paste")
			(net "GND")
		)
	)
)
